# SCM (Grand Teton) — schematic netlist excerpt (pin names and nets, part order shuffled) for the footprints in the layout excerpt that follows; sources: Cadence DE-HDL packaged netlist, KiCad conversion of 12092022_DA0F0TMDCD0_F0T_Management_Board_D_brd_V3_OCP.brd

R649  Q_RES  33.2 1% EMPTY  pkg 0402LF  page 21 : A = EMMC_DT0_R ; B = BMC_EMMC_DT0
C289  Q_CAP  10UF 25V 10% X6S  pkg C0805  page 53 : A = P2V5_AUX ; B = GND

(kicad_pcb
	(version 20260206)
	(generator "pcbnew")
	(generator_version "10.0")
	(general
		(thickness 1.6)
		(legacy_teardrops no)
	)
	(paper "A4")
	(title_block
		(title "12092022_DA0F0TMDCD0_F0T_Management_Board_D_brd_V3_OCP.brd")
		(comment 1 "Grand Teton / footprints 336-337 of 1440")
	)
	(layers
		(0 "F.Cu" signal "TOP")
		(4 "In1.Cu" signal "GND")
		(6 "In2.Cu" signal "IN1")
		(8 "In3.Cu" signal "GND1")
		(10 "In4.Cu" signal "IN2")
		(12 "In5.Cu" signal "VCC")
		(14 "In6.Cu" signal "VCC1")
		(16 "In7.Cu" signal "IN3")
		(18 "In8.Cu" signal "GND2")
		(20 "In9.Cu" signal "IN4")
		(22 "In10.Cu" signal "GND3")
		(2 "B.Cu" signal "BOTTOM")
		(9 "F.Adhes" user "F.Adhesive")
		(11 "B.Adhes" user "B.Adhesive")
		(13 "F.Paste" user "Package Geometry/Pastemask Top")
		(15 "B.Paste" user "Package Geometry/Pastemask Bottom")
		(5 "F.SilkS" user "Ref Des/Silkscreen Top")
		(7 "B.SilkS" user "Ref Des/Silkscreen Bottom")
		(1 "F.Mask" user "Board Geometry/Soldermask Top")
		(3 "B.Mask" user "Board Geometry/Soldermask Bottom")
		(17 "Dwgs.User" user "User.Drawings")
		(19 "Cmts.User" user "User.Comments")
		(21 "Eco1.User" user "User.Eco1")
		(23 "Eco2.User" user "User.Eco2")
		(25 "Edge.Cuts" user "Board Geometry/Outline")
		(27 "Margin" user)
		(31 "F.CrtYd" user "Package Geometry/Place Bound Top")
		(29 "B.CrtYd" user "Package Geometry/Place Bound Bottom")
		(35 "F.Fab" user "Ref Des/Assembly Top")
		(33 "B.Fab" user "Ref Des/Assembly Bottom")
	)
	(footprint ""
		(layer "F.Cu")
		(at 38.079172 -83.816952 90)
		(property "Reference" "R649"
			(at 0 0 90)
			(layer "F.SilkS")
			(hide yes)
			(effects
				(font
					(size 1.27 1.27)
				)
			)
		)
		(property "Value" ""
			(at 0 0 90)
			(layer "F.Fab")
			(effects
				(font
					(size 1.27 1.27)
				)
			)
		)
		(duplicate_pad_numbers_are_jumpers no)
		(fp_line
			(start 0.7874 -0.4064)
			(end 0.7874 0.4064)
			(stroke
				(width 0.1524)
				(type default)
			)
			(layer "F.SilkS")
		)
		(fp_line
			(start -0.7874 -0.4064)
			(end 0.7874 -0.4064)
			(stroke
				(width 0.1524)
				(type default)
			)
			(layer "F.SilkS")
		)
		(fp_line
			(start 0.7874 0.4064)
			(end -0.7874 0.4064)
			(stroke
				(width 0.1524)
				(type default)
			)
			(layer "F.SilkS")
		)
		(fp_line
			(start -0.7874 0.4064)
			(end -0.7874 -0.4064)
			(stroke
				(width 0.1524)
				(type default)
			)
			(layer "F.SilkS")
		)
		(fp_line
			(start -0.12065 -0.305054)
			(end -0.12065 -0.2794)
			(stroke
				(width 0.1)
				(type default)
			)
			(layer "F.Fab")
		)
		(fp_line
			(start -0.67945 -0.305054)
			(end -0.12065 -0.305054)
			(stroke
				(width 0.1)
				(type default)
			)
			(layer "F.Fab")
		)
		(fp_line
			(start 0.67945 -0.3048)
			(end 0.67945 0.3048)
			(stroke
				(width 0.1)
				(type default)
			)
			(layer "F.Fab")
		)
		(fp_line
			(start 0.12065 -0.3048)
			(end 0.67945 -0.3048)
			(stroke
				(width 0.1)
				(type default)
			)
			(layer "F.Fab")
		)
		(fp_line
			(start 0.12065 -0.2794)
			(end 0.12065 -0.3048)
			(stroke
				(width 0.1)
				(type default)
			)
			(layer "F.Fab")
		)
		(fp_line
			(start -0.12065 -0.2794)
			(end 0.12065 -0.2794)
			(stroke
				(width 0.1)
				(type default)
			)
			(layer "F.Fab")
		)
		(fp_line
			(start 0.120396 0.2794)
			(end -0.12065 0.2794)
			(stroke
				(width 0.1)
				(type default)
			)
			(layer "F.Fab")
		)
		(fp_line
			(start -0.12065 0.2794)
			(end -0.12065 0.3048)
			(stroke
				(width 0.1)
				(type default)
			)
			(layer "F.Fab")
		)
		(fp_line
			(start 0.67945 0.3048)
			(end 0.120396 0.3048)
			(stroke
				(width 0.1)
				(type default)
			)
			(layer "F.Fab")
		)
		(fp_line
			(start 0.120396 0.3048)
			(end 0.120396 0.2794)
			(stroke
				(width 0.1)
				(type default)
			)
			(layer "F.Fab")
		)
		(fp_line
			(start -0.12065 0.3048)
			(end -0.67945 0.3048)
			(stroke
				(width 0.1)
				(type default)
			)
			(layer "F.Fab")
		)
		(fp_line
			(start -0.67945 0.3048)
			(end -0.67945 -0.305054)
			(stroke
				(width 0.1)
				(type default)
			)
			(layer "F.Fab")
		)
		(pad "1" smd circle
			(at -0.40005 0 90)
			(size 0 0)
			(layers "F.Cu" "F.Mask" "F.Paste")
			(net "EMMC_DT0_R")
		)
		(pad "2" smd circle
			(at 0.40005 0 90)
			(size 0 0)
			(layers "F.Cu" "F.Mask" "F.Paste")
			(net "BMC_EMMC_DT0")
		)
	)
	(footprint ""
		(layer "F.Cu")
		(at 85.471 -34.544 -90)
		(property "Reference" "C289"
			(at 0 0 270)
			(layer "F.SilkS")
			(hide yes)
			(effects
				(font
					(size 1.27 1.27)
				)
			)
		)
		(property "Value" ""
			(at 0 0 270)
			(layer "F.Fab")
			(effects
				(font
					(size 1.27 1.27)
				)
			)
		)
		(duplicate_pad_numbers_are_jumpers no)
		(fp_line
			(start -1.651 0.8382)
			(end -1.651 -0.8382)
			(stroke
				(width 0.1524)
				(type default)
			)
			(layer "F.SilkS")
		)
		(fp_line
			(start 0 0.8382)
			(end 0 -0.8382)
			(stroke
				(width 0.1524)
				(type default)
			)
			(layer "F.SilkS")
		)
		(fp_line
			(start 1.651 0.8382)
			(end -1.651 0.8382)
			(stroke
				(width 0.1524)
				(type default)
			)
			(layer "F.SilkS")
		)
		(fp_line
			(start -1.651 -0.8382)
			(end 1.651 -0.8382)
			(stroke
				(width 0.1524)
				(type default)
			)
			(layer "F.SilkS")
		)
		(fp_line
			(start 1.651 -0.8382)
			(end 1.651 0.8382)
			(stroke
				(width 0.1524)
				(type default)
			)
			(layer "F.SilkS")
		)
		(fp_line
			(start -1.55956 0.7366)
			(end -1.524 0.7366)
			(stroke
				(width 0.1)
				(type default)
			)
			(layer "F.Fab")
		)
		(fp_line
			(start -1.524 0.7366)
			(end 1.524 0.7366)
			(stroke
				(width 0.1)
				(type default)
			)
			(layer "F.Fab")
		)
		(fp_line
			(start 1.524 0.7366)
			(end 1.55956 0.7366)
			(stroke
				(width 0.1)
				(type default)
			)
			(layer "F.Fab")
		)
		(fp_line
			(start 1.55956 0.7366)
			(end 1.55956 -0.7366)
			(stroke
				(width 0.1)
				(type default)
			)
			(layer "F.Fab")
		)
		(fp_line
			(start -1.55956 -0.7366)
			(end -1.55956 0.7366)
			(stroke
				(width 0.1)
				(type default)
			)
			(layer "F.Fab")
		)
		(fp_line
			(start -1.524 -0.7366)
			(end -1.55956 -0.7366)
			(stroke
				(width 0.1)
				(type default)
			)
			(layer "F.Fab")
		)
		(fp_line
			(start 1.524 -0.7366)
			(end -1.524 -0.7366)
			(stroke
				(width 0.1)
				(type default)
			)
			(layer "F.Fab")
		)
		(fp_line
			(start 1.55956 -0.7366)
			(end 1.524 -0.7366)
			(stroke
				(width 0.1)
				(type default)
			)
			(layer "F.Fab")
		)
		(pad "1" smd rect
			(at -0.94996 0 90)
			(size 1.1176 1.3716)
			(layers "F.Cu" "F.Mask" "F.Paste")
			(net "P2V5_AUX")
		)
		(pad "2" smd rect
			(at 0.94996 0 90)
			(size 1.1176 1.3716)
			(layers "F.Cu" "F.Mask" "F.Paste")
			(net "GND")
		)
	)
)
